(kicad_pcb
	(version 20260206)
	(generator "pcbnew")
	(generator_version "10.0")
	(general
		(thickness 1.6)
		(legacy_teardrops no)
	)
	(paper "A4")
	(title_block
		(title "01162023_DA0F0TEBIF0_F0T_Expander_BD_F_brd_V02_OCP.brd")
		(comment 1 "Grand Teton / footprints 4657-4663 of 9728")
	)
	(layers
		(0 "F.Cu" signal "TOP")
		(4 "In1.Cu" signal "GND")
		(6 "In2.Cu" signal "VCC")
		(8 "In3.Cu" signal "VCC1")
		(10 "In4.Cu" signal "GND1")
		(12 "In5.Cu" signal "IN1")
		(14 "In6.Cu" signal "GND2")
		(16 "In7.Cu" signal "IN2")
		(18 "In8.Cu" signal "GND3")
		(20 "In9.Cu" signal "IN3")
		(22 "In10.Cu" signal "GND4")
		(24 "In11.Cu" signal "IN4")
		(26 "In12.Cu" signal "GND5")
		(28 "In13.Cu" signal "IN5")
		(30 "In14.Cu" signal "GND6")
		(32 "In15.Cu" signal "IN6")
		(34 "In16.Cu" signal "GND7")
		(2 "B.Cu" signal "BOTTOM")
		(9 "F.Adhes" user "F.Adhesive")
		(11 "B.Adhes" user "B.Adhesive")
		(13 "F.Paste" user "Package Geometry/Pastemask Top")
		(15 "B.Paste" user "Package Geometry/Pastemask Bottom")
		(5 "F.SilkS" user "Ref Des/Silkscreen Top")
		(7 "B.SilkS" user "Ref Des/Silkscreen Bottom")
		(1 "F.Mask" user "Board Geometry/Soldermask Top")
		(3 "B.Mask" user "Board Geometry/Soldermask Bottom")
		(17 "Dwgs.User" user "User.Drawings")
		(19 "Cmts.User" user "User.Comments")
		(21 "Eco1.User" user "User.Eco1")
		(23 "Eco2.User" user "User.Eco2")
		(25 "Edge.Cuts" user "Board Geometry/Outline")
		(27 "Margin" user)
		(31 "F.CrtYd" user "Package Geometry/Place Bound Top")
		(29 "B.CrtYd" user "Package Geometry/Place Bound Bottom")
		(35 "F.Fab" user "Ref Des/Assembly Top")
		(33 "B.Fab" user "Ref Des/Assembly Bottom")
	)
	(footprint ""
		(layer "F.Cu")
		(at 82.661506 -132.601208 180)
		(property "Reference" "C21"
			(at 0 0 180)
			(layer "F.SilkS")
			(hide yes)
			(effects
				(font
					(size 1.27 1.27)
				)
			)
		)
		(property "Value" ""
			(at 0 0 180)
			(layer "F.Fab")
			(effects
				(font
					(size 1.27 1.27)
				)
			)
		)
		(duplicate_pad_numbers_are_jumpers no)
		(fp_line
			(start 0.299974 0.150114)
			(end -0.299974 0.150114)
			(stroke
				(width 0.1)
				(type default)
			)
			(layer "F.Fab")
		)
		(fp_line
			(start 0.299974 -0.150114)
			(end 0.299974 0.150114)
			(stroke
				(width 0.1)
				(type default)
			)
			(layer "F.Fab")
		)
		(fp_line
			(start -0.299974 0.150114)
			(end -0.299974 -0.150114)
			(stroke
				(width 0.1)
				(type default)
			)
			(layer "F.Fab")
		)
		(fp_line
			(start -0.299974 -0.150114)
			(end 0.299974 -0.150114)
			(stroke
				(width 0.1)
				(type default)
			)
			(layer "F.Fab")
		)
		(pad "1" smd rect
			(at -0.2667 0 180)
			(size 0.3048 0.381)
			(layers "F.Cu" "F.Mask" "F.Paste")
			(net "P5E_PEX0_STN0_TX_DP<5>")
		)
		(pad "2" smd rect
			(at 0.2667 0 180)
			(size 0.3048 0.381)
			(layers "F.Cu" "F.Mask" "F.Paste")
			(net "P5E_PEX0_STN0_TX_C_DP<5>")
		)
	)
	(footprint ""
		(layer "F.Cu")
		(at 7.613396 -136.328404 180)
		(property "Reference" "PC360"
			(at 0 0 180)
			(layer "F.SilkS")
			(hide yes)
			(effects
				(font
					(size 1.27 1.27)
				)
			)
		)
		(property "Value" ""
			(at 0 0 180)
			(layer "F.Fab")
			(effects
				(font
					(size 1.27 1.27)
				)
			)
		)
		(duplicate_pad_numbers_are_jumpers no)
		(fp_line
			(start 0.7874 0.4064)
			(end -0.7874 0.4064)
			(stroke
				(width 0.1524)
				(type default)
			)
			(layer "F.SilkS")
		)
		(fp_line
			(start 0.7874 -0.4064)
			(end 0.7874 0.4064)
			(stroke
				(width 0.1524)
				(type default)
			)
			(layer "F.SilkS")
		)
		(fp_line
			(start -0.7874 0.4064)
			(end -0.7874 -0.4064)
			(stroke
				(width 0.1524)
				(type default)
			)
			(layer "F.SilkS")
		)
		(fp_line
			(start -0.7874 -0.4064)
			(end 0.7874 -0.4064)
			(stroke
				(width 0.1524)
				(type default)
			)
			(layer "F.SilkS")
		)
		(fp_line
			(start 0.67945 0.3048)
			(end 0.120396 0.3048)
			(stroke
				(width 0.1)
				(type default)
			)
			(layer "F.Fab")
		)
		(fp_line
			(start 0.67945 -0.3048)
			(end 0.67945 0.3048)
			(stroke
				(width 0.1)
				(type default)
			)
			(layer "F.Fab")
		)
		(fp_line
			(start 0.12065 -0.2794)
			(end 0.12065 -0.3048)
			(stroke
				(width 0.1)
				(type default)
			)
			(layer "F.Fab")
		)
		(fp_line
			(start 0.12065 -0.3048)
			(end 0.67945 -0.3048)
			(stroke
				(width 0.1)
				(type default)
			)
			(layer "F.Fab")
		)
		(fp_line
			(start 0.120396 0.3048)
			(end 0.120396 0.2794)
			(stroke
				(width 0.1)
				(type default)
			)
			(layer "F.Fab")
		)
		(fp_line
			(start 0.120396 0.2794)
			(end -0.12065 0.2794)
			(stroke
				(width 0.1)
				(type default)
			)
			(layer "F.Fab")
		)
		(fp_line
			(start -0.12065 0.3048)
			(end -0.67945 0.3048)
			(stroke
				(width 0.1)
				(type default)
			)
			(layer "F.Fab")
		)
		(fp_line
			(start -0.12065 0.2794)
			(end -0.12065 0.3048)
			(stroke
				(width 0.1)
				(type default)
			)
			(layer "F.Fab")
		)
		(fp_line
			(start -0.12065 -0.2794)
			(end 0.12065 -0.2794)
			(stroke
				(width 0.1)
				(type default)
			)
			(layer "F.Fab")
		)
		(fp_line
			(start -0.12065 -0.305054)
			(end -0.12065 -0.2794)
			(stroke
				(width 0.1)
				(type default)
			)
			(layer "F.Fab")
		)
		(fp_line
			(start -0.67945 0.3048)
			(end -0.67945 -0.305054)
			(stroke
				(width 0.1)
				(type default)
			)
			(layer "F.Fab")
		)
		(fp_line
			(start -0.67945 -0.305054)
			(end -0.12065 -0.305054)
			(stroke
				(width 0.1)
				(type default)
			)
			(layer "F.Fab")
		)
		(pad "1" smd circle
			(at -0.40005 0 180)
			(size 0 0)
			(layers "F.Cu" "F.Mask" "F.Paste")
			(net "P5V_AUX")
		)
		(pad "2" smd circle
			(at 0.40005 0 180)
			(size 0 0)
			(layers "F.Cu" "F.Mask" "F.Paste")
			(net "GND")
		)
	)
	(footprint ""
		(layer "F.Cu")
		(at 71.246746 -37.47516)
		(property "Reference" "R5887"
			(at 0 0 0)
			(layer "F.SilkS")
			(hide yes)
			(effects
				(font
					(size 1.27 1.27)
				)
			)
		)
		(property "Value" ""
			(at 0 0 0)
			(layer "F.Fab")
			(effects
				(font
					(size 1.27 1.27)
				)
			)
		)
		(duplicate_pad_numbers_are_jumpers no)
		(fp_line
			(start -0.7874 -0.4064)
			(end 0.7874 -0.4064)
			(stroke
				(width 0.1524)
				(type default)
			)
			(layer "F.SilkS")
		)
		(fp_line
			(start -0.7874 0.4064)
			(end -0.7874 -0.4064)
			(stroke
				(width 0.1524)
				(type default)
			)
			(layer "F.SilkS")
		)
		(fp_line
			(start 0.7874 -0.4064)
			(end 0.7874 0.4064)
			(stroke
				(width 0.1524)
				(type default)
			)
			(layer "F.SilkS")
		)
		(fp_line
			(start 0.7874 0.4064)
			(end -0.7874 0.4064)
			(stroke
				(width 0.1524)
				(type default)
			)
			(layer "F.SilkS")
		)
		(fp_line
			(start -0.67945 -0.305054)
			(end -0.12065 -0.305054)
			(stroke
				(width 0.1)
				(type default)
			)
			(layer "F.Fab")
		)
		(fp_line
			(start -0.67945 0.3048)
			(end -0.67945 -0.305054)
			(stroke
				(width 0.1)
				(type default)
			)
			(layer "F.Fab")
		)
		(fp_line
			(start -0.12065 -0.305054)
			(end -0.12065 -0.2794)
			(stroke
				(width 0.1)
				(type default)
			)
			(layer "F.Fab")
		)
		(fp_line
			(start -0.12065 -0.2794)
			(end 0.12065 -0.2794)
			(stroke
				(width 0.1)
				(type default)
			)
			(layer "F.Fab")
		)
		(fp_line
			(start -0.12065 0.2794)
			(end -0.12065 0.3048)
			(stroke
				(width 0.1)
				(type default)
			)
			(layer "F.Fab")
		)
		(fp_line
			(start -0.12065 0.3048)
			(end -0.67945 0.3048)
			(stroke
				(width 0.1)
				(type default)
			)
			(layer "F.Fab")
		)
		(fp_line
			(start 0.120396 0.2794)
			(end -0.12065 0.2794)
			(stroke
				(width 0.1)
				(type default)
			)
			(layer "F.Fab")
		)
		(fp_line
			(start 0.120396 0.3048)
			(end 0.120396 0.2794)
			(stroke
				(width 0.1)
				(type default)
			)
			(layer "F.Fab")
		)
		(fp_line
			(start 0.12065 -0.3048)
			(end 0.67945 -0.3048)
			(stroke
				(width 0.1)
				(type default)
			)
			(layer "F.Fab")
		)
		(fp_line
			(start 0.12065 -0.2794)
			(end 0.12065 -0.3048)
			(stroke
				(width 0.1)
				(type default)
			)
			(layer "F.Fab")
		)
		(fp_line
			(start 0.67945 -0.3048)
			(end 0.67945 0.3048)
			(stroke
				(width 0.1)
				(type default)
			)
			(layer "F.Fab")
		)
		(fp_line
			(start 0.67945 0.3048)
			(end 0.120396 0.3048)
			(stroke
				(width 0.1)
				(type default)
			)
			(layer "F.Fab")
		)
		(pad "1" smd circle
			(at -0.40005 0)
			(size 0 0)
			(layers "F.Cu" "F.Mask" "F.Paste")
			(net "P3V3_SSD3")
		)
		(pad "2" smd circle
			(at 0.40005 0)
			(size 0 0)
			(layers "F.Cu" "F.Mask" "F.Paste")
			(net "P3V3_SSD3_PG_G1")
		)
	)
	(footprint ""
		(layer "F.Cu")
		(at 367.525808 -159.082994 -90)
		(property "Reference" "PD5"
			(at 4.244594 -2.756662 90)
			(unlocked yes)
			(layer "F.SilkS")
			(effects
				(font
					(size 0.7874 0.5842)
					(thickness 0.1524)
				)
				(justify left)
			)
		)
		(property "Value" ""
			(at 0 0 270)
			(layer "F.Fab")
			(effects
				(font
					(size 1.27 1.27)
				)
			)
		)
		(duplicate_pad_numbers_are_jumpers no)
		(fp_line
			(start -3.656584 1.970024)
			(end 4.240784 1.970024)
			(stroke
				(width 0.1524)
				(type default)
			)
			(layer "F.SilkS")
		)
		(fp_line
			(start 4.240784 1.970024)
			(end 4.240784 -1.970024)
			(stroke
				(width 0.1524)
				(type default)
			)
			(layer "F.SilkS")
		)
		(fp_line
			(start -3.656584 -1.970024)
			(end -3.656584 1.970024)
			(stroke
				(width 0.1524)
				(type default)
			)
			(layer "F.SilkS")
		)
		(fp_line
			(start 4.240784 -1.970024)
			(end -3.656584 -1.970024)
			(stroke
				(width 0.1524)
				(type default)
			)
			(layer "F.SilkS")
		)
		(fp_poly
			(pts
				(xy 3.580384 1.970024) (xy 3.580384 -1.970024) (xy 4.240784 -1.970024) (xy 4.240784 1.970024)
			)
			(stroke
				(width 0)
				(type default)
			)
			(fill yes)
			(layer "F.SilkS")
		)
		(fp_line
			(start -2.3749 1.970024)
			(end 2.3749 1.970024)
			(stroke
				(width 0.1)
				(type default)
			)
			(layer "F.Fab")
		)
		(fp_line
			(start 2.3749 1.970024)
			(end 2.3749 -1.970024)
			(stroke
				(width 0.1)
				(type default)
			)
			(layer "F.Fab")
		)
		(fp_line
			(start -2.3749 -1.970024)
			(end -2.3749 1.970024)
			(stroke
				(width 0.1)
				(type default)
			)
			(layer "F.Fab")
		)
		(fp_line
			(start 2.3749 -1.970024)
			(end -2.3749 -1.970024)
			(stroke
				(width 0.1)
				(type default)
			)
			(layer "F.Fab")
		)
		(fp_text user "+"
			(at -4.9784 -0.23495 270)
			(unlocked yes)
			(layer "F.Fab")
			(effects
				(font
					(size 1.905 1.4224)
					(thickness 0.1524)
				)
				(justify left)
			)
		)
		(fp_text user "-"
			(at 4.1656 -0.23495 270)
			(unlocked yes)
			(layer "F.Fab")
			(effects
				(font
					(size 1.905 1.4224)
					(thickness 0.1524)
				)
				(justify left)
			)
		)
		(pad "A" smd rect
			(at -2.450084 0 270)
			(size 2.159 2.2606)
			(layers "F.Cu" "F.Mask" "F.Paste")
			(net "GND")
		)
		(pad "C" smd rect
			(at 2.450084 0 270)
			(size 2.159 2.2606)
			(layers "F.Cu" "F.Mask" "F.Paste")
			(net "P12V_AUX")
		)
	)
	(footprint ""
		(layer "F.Cu")
		(at 170.554904 -22.961346 90)
		(property "Reference" "R1662"
			(at 0 0 90)
			(layer "F.SilkS")
			(hide yes)
			(effects
				(font
					(size 1.27 1.27)
				)
			)
		)
		(property "Value" ""
			(at 0 0 90)
			(layer "F.Fab")
			(effects
				(font
					(size 1.27 1.27)
				)
			)
		)
		(duplicate_pad_numbers_are_jumpers no)
		(fp_line
			(start 0.7874 -0.4064)
			(end 0.7874 0.4064)
			(stroke
				(width 0.1524)
				(type default)
			)
			(layer "F.SilkS")
		)
		(fp_line
			(start -0.7874 -0.4064)
			(end 0.7874 -0.4064)
			(stroke
				(width 0.1524)
				(type default)
			)
			(layer "F.SilkS")
		)
		(fp_line
			(start 0.7874 0.4064)
			(end -0.7874 0.4064)
			(stroke
				(width 0.1524)
				(type default)
			)
			(layer "F.SilkS")
		)
		(fp_line
			(start -0.7874 0.4064)
			(end -0.7874 -0.4064)
			(stroke
				(width 0.1524)
				(type default)
			)
			(layer "F.SilkS")
		)
		(fp_line
			(start -0.12065 -0.305054)
			(end -0.12065 -0.2794)
			(stroke
				(width 0.1)
				(type default)
			)
			(layer "F.Fab")
		)
		(fp_line
			(start -0.67945 -0.305054)
			(end -0.12065 -0.305054)
			(stroke
				(width 0.1)
				(type default)
			)
			(layer "F.Fab")
		)
		(fp_line
			(start 0.67945 -0.3048)
			(end 0.67945 0.3048)
			(stroke
				(width 0.1)
				(type default)
			)
			(layer "F.Fab")
		)
		(fp_line
			(start 0.12065 -0.3048)
			(end 0.67945 -0.3048)
			(stroke
				(width 0.1)
				(type default)
			)
			(layer "F.Fab")
		)
		(fp_line
			(start 0.12065 -0.2794)
			(end 0.12065 -0.3048)
			(stroke
				(width 0.1)
				(type default)
			)
			(layer "F.Fab")
		)
		(fp_line
			(start -0.12065 -0.2794)
			(end 0.12065 -0.2794)
			(stroke
				(width 0.1)
				(type default)
			)
			(layer "F.Fab")
		)
		(fp_line
			(start 0.120396 0.2794)
			(end -0.12065 0.2794)
			(stroke
				(width 0.1)
				(type default)
			)
			(layer "F.Fab")
		)
		(fp_line
			(start -0.12065 0.2794)
			(end -0.12065 0.3048)
			(stroke
				(width 0.1)
				(type default)
			)
			(layer "F.Fab")
		)
		(fp_line
			(start 0.67945 0.3048)
			(end 0.120396 0.3048)
			(stroke
				(width 0.1)
				(type default)
			)
			(layer "F.Fab")
		)
		(fp_line
			(start 0.120396 0.3048)
			(end 0.120396 0.2794)
			(stroke
				(width 0.1)
				(type default)
			)
			(layer "F.Fab")
		)
		(fp_line
			(start -0.12065 0.3048)
			(end -0.67945 0.3048)
			(stroke
				(width 0.1)
				(type default)
			)
			(layer "F.Fab")
		)
		(fp_line
			(start -0.67945 0.3048)
			(end -0.67945 -0.305054)
			(stroke
				(width 0.1)
				(type default)
			)
			(layer "F.Fab")
		)
		(pad "1" smd circle
			(at -0.40005 0 90)
			(size 0 0)
			(layers "F.Cu" "F.Mask" "F.Paste")
			(net "SMB_SSD5_ISO_EN")
		)
		(pad "2" smd circle
			(at 0.40005 0 90)
			(size 0 0)
			(layers "F.Cu" "F.Mask" "F.Paste")
			(net "P3V3_AUX")
		)
	)
	(footprint ""
		(layer "F.Cu")
		(at 99.530408 -66.32194 -90)
		(property "Reference" "PC657"
			(at 0 0 270)
			(layer "F.SilkS")
			(hide yes)
			(effects
				(font
					(size 1.27 1.27)
				)
			)
		)
		(property "Value" ""
			(at 0 0 270)
			(layer "F.Fab")
			(effects
				(font
					(size 1.27 1.27)
				)
			)
		)
		(duplicate_pad_numbers_are_jumpers no)
		(fp_line
			(start -0.7874 0.4064)
			(end -0.7874 -0.4064)
			(stroke
				(width 0.1524)
				(type default)
			)
			(layer "F.SilkS")
		)
		(fp_line
			(start 0.7874 0.4064)
			(end -0.7874 0.4064)
			(stroke
				(width 0.1524)
				(type default)
			)
			(layer "F.SilkS")
		)
		(fp_line
			(start -0.7874 -0.4064)
			(end 0.7874 -0.4064)
			(stroke
				(width 0.1524)
				(type default)
			)
			(layer "F.SilkS")
		)
		(fp_line
			(start 0.7874 -0.4064)
			(end 0.7874 0.4064)
			(stroke
				(width 0.1524)
				(type default)
			)
			(layer "F.SilkS")
		)
		(fp_line
			(start -0.67945 0.3048)
			(end -0.67945 -0.305054)
			(stroke
				(width 0.1)
				(type default)
			)
			(layer "F.Fab")
		)
		(fp_line
			(start -0.12065 0.3048)
			(end -0.67945 0.3048)
			(stroke
				(width 0.1)
				(type default)
			)
			(layer "F.Fab")
		)
		(fp_line
			(start 0.120396 0.3048)
			(end 0.120396 0.2794)
			(stroke
				(width 0.1)
				(type default)
			)
			(layer "F.Fab")
		)
		(fp_line
			(start 0.67945 0.3048)
			(end 0.120396 0.3048)
			(stroke
				(width 0.1)
				(type default)
			)
			(layer "F.Fab")
		)
		(fp_line
			(start -0.12065 0.2794)
			(end -0.12065 0.3048)
			(stroke
				(width 0.1)
				(type default)
			)
			(layer "F.Fab")
		)
		(fp_line
			(start 0.120396 0.2794)
			(end -0.12065 0.2794)
			(stroke
				(width 0.1)
				(type default)
			)
			(layer "F.Fab")
		)
		(fp_line
			(start -0.12065 -0.2794)
			(end 0.12065 -0.2794)
			(stroke
				(width 0.1)
				(type default)
			)
			(layer "F.Fab")
		)
		(fp_line
			(start 0.12065 -0.2794)
			(end 0.12065 -0.3048)
			(stroke
				(width 0.1)
				(type default)
			)
			(layer "F.Fab")
		)
		(fp_line
			(start 0.12065 -0.3048)
			(end 0.67945 -0.3048)
			(stroke
				(width 0.1)
				(type default)
			)
			(layer "F.Fab")
		)
		(fp_line
			(start 0.67945 -0.3048)
			(end 0.67945 0.3048)
			(stroke
				(width 0.1)
				(type default)
			)
			(layer "F.Fab")
		)
		(fp_line
			(start -0.67945 -0.305054)
			(end -0.12065 -0.305054)
			(stroke
				(width 0.1)
				(type default)
			)
			(layer "F.Fab")
		)
		(fp_line
			(start -0.12065 -0.305054)
			(end -0.12065 -0.2794)
			(stroke
				(width 0.1)
				(type default)
			)
			(layer "F.Fab")
		)
		(pad "1" smd circle
			(at -0.40005 0 270)
			(size 0 0)
			(layers "F.Cu" "F.Mask" "F.Paste")
			(net "P12V_SSD3_CO_DV_DT")
		)
		(pad "2" smd circle
			(at 0.40005 0 270)
			(size 0 0)
			(layers "F.Cu" "F.Mask" "F.Paste")
			(net "GND")
		)
	)
	(footprint ""
		(layer "F.Cu")
		(at 373.761 -181.483 90)
		(property "Reference" "C3599"
			(at 0 0 90)
			(layer "F.SilkS")
			(hide yes)
			(effects
				(font
					(size 1.27 1.27)
				)
			)
		)
		(property "Value" ""
			(at 0 0 90)
			(layer "F.Fab")
			(effects
				(font
					(size 1.27 1.27)
				)
			)
		)
		(duplicate_pad_numbers_are_jumpers no)
		(fp_line
			(start 0.7874 -0.4064)
			(end 0.7874 0.4064)
			(stroke
				(width 0.1524)
				(type default)
			)
			(layer "F.SilkS")
		)
		(fp_line
			(start -0.7874 -0.4064)
			(end 0.7874 -0.4064)
			(stroke
				(width 0.1524)
				(type default)
			)
			(layer "F.SilkS")
		)
		(fp_line
			(start 0.7874 0.4064)
			(end -0.7874 0.4064)
			(stroke
				(width 0.1524)
				(type default)
			)
			(layer "F.SilkS")
		)
		(fp_line
			(start -0.7874 0.4064)
			(end -0.7874 -0.4064)
			(stroke
				(width 0.1524)
				(type default)
			)
			(layer "F.SilkS")
		)
		(fp_line
			(start -0.12065 -0.305054)
			(end -0.12065 -0.2794)
			(stroke
				(width 0.1)
				(type default)
			)
			(layer "F.Fab")
		)
		(fp_line
			(start -0.67945 -0.305054)
			(end -0.12065 -0.305054)
			(stroke
				(width 0.1)
				(type default)
			)
			(layer "F.Fab")
		)
		(fp_line
			(start 0.67945 -0.3048)
			(end 0.67945 0.3048)
			(stroke
				(width 0.1)
				(type default)
			)
			(layer "F.Fab")
		)
		(fp_line
			(start 0.12065 -0.3048)
			(end 0.67945 -0.3048)
			(stroke
				(width 0.1)
				(type default)
			)
			(layer "F.Fab")
		)
		(fp_line
			(start 0.12065 -0.2794)
			(end 0.12065 -0.3048)
			(stroke
				(width 0.1)
				(type default)
			)
			(layer "F.Fab")
		)
		(fp_line
			(start -0.12065 -0.2794)
			(end 0.12065 -0.2794)
			(stroke
				(width 0.1)
				(type default)
			)
			(layer "F.Fab")
		)
		(fp_line
			(start 0.120396 0.2794)
			(end -0.12065 0.2794)
			(stroke
				(width 0.1)
				(type default)
			)
			(layer "F.Fab")
		)
		(fp_line
			(start -0.12065 0.2794)
			(end -0.12065 0.3048)
			(stroke
				(width 0.1)
				(type default)
			)
			(layer "F.Fab")
		)
		(fp_line
			(start 0.67945 0.3048)
			(end 0.120396 0.3048)
			(stroke
				(width 0.1)
				(type default)
			)
			(layer "F.Fab")
		)
		(fp_line
			(start 0.120396 0.3048)
			(end 0.120396 0.2794)
			(stroke
				(width 0.1)
				(type default)
			)
			(layer "F.Fab")
		)
		(fp_line
			(start -0.12065 0.3048)
			(end -0.67945 0.3048)
			(stroke
				(width 0.1)
				(type default)
			)
			(layer "F.Fab")
		)
		(fp_line
			(start -0.67945 0.3048)
			(end -0.67945 -0.305054)
			(stroke
				(width 0.1)
				(type default)
			)
			(layer "F.Fab")
		)
		(pad "1" smd circle
			(at -0.40005 0 90)
			(size 0 0)
			(layers "F.Cu" "F.Mask" "F.Paste")
			(net "P3V3_AUX")
		)
		(pad "2" smd circle
			(at 0.40005 0 90)
			(size 0 0)
			(layers "F.Cu" "F.Mask" "F.Paste")
			(net "GND")
		)
	)
)
